FILE_TYPE = MACRO_DRAWING;
SET COLOR_WIRE YELLOW;
SET COLOR_PROP ORANGE;
SET COLOR_DOT WHITE;
SET COLOR_ARC YELLOW;
SET COLOR_BODY GREEN;
SET COLOR_NOTE PURPLE;
SET PROP_DISPLAY VALUE;
SET PAGE_NUMBER P457;
FORCEADD QUANTA_TITLE_BLOCK_C..1
(0 0);
FORCEPROP 1 LAST CUSTOM_TXT_CDS <NAME_2>
J 0
(-3175 50);
FORCEPROP 1 LAST CUSTOM_TXT_CDS <NAME_1>
J 0
(-3175 175);
FORCEPROP 1 LAST CUSTOM_TXT_CDS <Q_NUMBER>
J 0
(-1403 103);
DISPLAY 1.212766 (-1403 103);
FORCEPROP 1 LAST CUSTOM_TXT_CDS <Q_PROJ>
J 0
(-2382 102);
DISPLAY 1.212766 (-2382 102);
FORCEPROP 1 LAST CUSTOM_TXT_CDS <Q_REV>
J 0
(-184 103);
DISPLAY 1.212766 (-184 103);
FORCEPROP 1 LAST CUSTOM_TXT_CDS <CON_LAST_MODIFIED>
J 0
(-1885 15);
DISPLAY 0.978723 (-1885 15);
FORCEPROP 1 LAST CUSTOM_TXT_CDS <CON_PAGE_NUM> OF <CON_TOTAL_PAGES>
J 0
(-446 18);
DISPLAY 0.978723 (-446 18);
FORCEPROP 1 LAST Q_TITLE BLANK
J 0
(-9366 26);
DISPLAY 2.446809 (-9366 26);
PAINT GREEN (-9366 26);
FORCEPROP 2 LAST CDS_LIB pure_quanta
J 0
(0 0);
DISPLAY INVISIBLE (0 0);
FORCEPROP 1 LAST CDS_LMAN_SYM_OUTLINE -9475,6775,100,-125
J 0
(0 0);
DISPLAY 0.468085 (0 0);
PAINT GREEN (0 0);
DISPLAY INVISIBLE (0 0);
FORCEPROP 2 LAST PAGE_BORDER TRUE
J 0
(-7890 5250);
DISPLAY 0.638298 (-7890 5250);
PAINT PINK (-7890 5250);
DISPLAY INVISIBLE (-7890 5250);
FORCEPROP 2 LAST CDS_XR_PAGE_TITLE CR-349 : @T6G_MB_LIB.T6G(SCH_1):PAGE349
J 0
(-7890 5250);
DISPLAY 0.638298 (-7890 5250);
PAINT PINK (-7890 5250);
DISPLAY INVISIBLE (-7890 5250);
FORCEPROP 2 LAST CUSTOM_TXT_CDS <XR_PAGE_TITLE>
J 0
(-7890 5250);
DISPLAY 0.638298 (-7890 5250);
PAINT PINK (-7890 5250);
DISPLAY INVISIBLE (-7890 5250);
FORCEPROP 1 LAST COMMENT_BODY TRUE
J 0
(12 -13);
DISPLAY 0.978723 (12 -13);
PAINT GREEN (12 -13);
DISPLAY INVISIBLE (12 -13);
FORCEPROP 1 LAST Q_DEPT BU9
J 1
(-3763 49);
DISPLAY 1.957447 (-3763 49);
PAINT GREEN (-3763 49);
DISPLAY INVISIBLE (-3763 49);
FORCEPROP 0 LAST CDS_CON_LAST_MODIFIED Thu Aug 24 10:17:05 2023
J 0
(-1885 15);
DISPLAY INVISIBLE (-1885 15);
QUIT
